(kicad_pcb
	(version 20260206)
	(generator "pcbnew")
	(generator_version "10.0")
	(general
		(thickness 1.6)
		(legacy_teardrops no)
	)
	(paper "A4")
	(title_block
		(title "01162023_DA0F0TEBIF0_F0T_Expander_BD_F_brd_V02_OCP.brd")
		(comment 1 "Grand Teton / footprints 7254-7260 of 9728")
	)
	(layers
		(0 "F.Cu" signal "TOP")
		(4 "In1.Cu" signal "GND")
		(6 "In2.Cu" signal "VCC")
		(8 "In3.Cu" signal "VCC1")
		(10 "In4.Cu" signal "GND1")
		(12 "In5.Cu" signal "IN1")
		(14 "In6.Cu" signal "GND2")
		(16 "In7.Cu" signal "IN2")
		(18 "In8.Cu" signal "GND3")
		(20 "In9.Cu" signal "IN3")
		(22 "In10.Cu" signal "GND4")
		(24 "In11.Cu" signal "IN4")
		(26 "In12.Cu" signal "GND5")
		(28 "In13.Cu" signal "IN5")
		(30 "In14.Cu" signal "GND6")
		(32 "In15.Cu" signal "IN6")
		(34 "In16.Cu" signal "GND7")
		(2 "B.Cu" signal "BOTTOM")
		(9 "F.Adhes" user "F.Adhesive")
		(11 "B.Adhes" user "B.Adhesive")
		(13 "F.Paste" user "Package Geometry/Pastemask Top")
		(15 "B.Paste" user "Package Geometry/Pastemask Bottom")
		(5 "F.SilkS" user "Ref Des/Silkscreen Top")
		(7 "B.SilkS" user "Ref Des/Silkscreen Bottom")
		(1 "F.Mask" user "Board Geometry/Soldermask Top")
		(3 "B.Mask" user "Board Geometry/Soldermask Bottom")
		(17 "Dwgs.User" user "User.Drawings")
		(19 "Cmts.User" user "User.Comments")
		(21 "Eco1.User" user "User.Eco1")
		(23 "Eco2.User" user "User.Eco2")
		(25 "Edge.Cuts" user "Board Geometry/Outline")
		(27 "Margin" user)
		(31 "F.CrtYd" user "Package Geometry/Place Bound Top")
		(29 "B.CrtYd" user "Package Geometry/Place Bound Bottom")
		(35 "F.Fab" user "Ref Des/Assembly Top")
		(33 "B.Fab" user "Ref Des/Assembly Bottom")
	)
	(footprint ""
		(layer "B.Cu")
		(at 214.454486 -213.222586 180)
		(property "Reference" "R5531"
			(at 0 0 0)
			(layer "B.SilkS")
			(hide yes)
			(effects
				(font
					(size 1.27 1.27)
				)
				(justify mirror)
			)
		)
		(property "Value" ""
			(at 0 0 0)
			(layer "B.Fab")
			(effects
				(font
					(size 1.27 1.27)
				)
				(justify mirror)
			)
		)
		(duplicate_pad_numbers_are_jumpers no)
		(fp_line
			(start 0.7874 0.4064)
			(end 0.7874 -0.4064)
			(stroke
				(width 0.1524)
				(type default)
			)
			(layer "B.SilkS")
		)
		(fp_line
			(start 0.7874 -0.4064)
			(end -0.7874 -0.4064)
			(stroke
				(width 0.1524)
				(type default)
			)
			(layer "B.SilkS")
		)
		(fp_line
			(start -0.7874 0.4064)
			(end 0.7874 0.4064)
			(stroke
				(width 0.1524)
				(type default)
			)
			(layer "B.SilkS")
		)
		(fp_line
			(start -0.7874 -0.4064)
			(end -0.7874 0.4064)
			(stroke
				(width 0.1524)
				(type default)
			)
			(layer "B.SilkS")
		)
		(fp_line
			(start 0.67945 0.3048)
			(end 0.67945 -0.305054)
			(stroke
				(width 0.1)
				(type default)
			)
			(layer "B.Fab")
		)
		(fp_line
			(start 0.67945 -0.305054)
			(end 0.12065 -0.305054)
			(stroke
				(width 0.1)
				(type default)
			)
			(layer "B.Fab")
		)
		(fp_line
			(start 0.12065 0.3048)
			(end 0.67945 0.3048)
			(stroke
				(width 0.1)
				(type default)
			)
			(layer "B.Fab")
		)
		(fp_line
			(start 0.12065 0.2794)
			(end 0.12065 0.3048)
			(stroke
				(width 0.1)
				(type default)
			)
			(layer "B.Fab")
		)
		(fp_line
			(start 0.12065 -0.2794)
			(end -0.12065 -0.2794)
			(stroke
				(width 0.1)
				(type default)
			)
			(layer "B.Fab")
		)
		(fp_line
			(start 0.12065 -0.305054)
			(end 0.12065 -0.2794)
			(stroke
				(width 0.1)
				(type default)
			)
			(layer "B.Fab")
		)
		(fp_line
			(start -0.120396 0.3048)
			(end -0.120396 0.2794)
			(stroke
				(width 0.1)
				(type default)
			)
			(layer "B.Fab")
		)
		(fp_line
			(start -0.120396 0.2794)
			(end 0.12065 0.2794)
			(stroke
				(width 0.1)
				(type default)
			)
			(layer "B.Fab")
		)
		(fp_line
			(start -0.12065 -0.2794)
			(end -0.12065 -0.3048)
			(stroke
				(width 0.1)
				(type default)
			)
			(layer "B.Fab")
		)
		(fp_line
			(start -0.12065 -0.3048)
			(end -0.67945 -0.3048)
			(stroke
				(width 0.1)
				(type default)
			)
			(layer "B.Fab")
		)
		(fp_line
			(start -0.67945 0.3048)
			(end -0.120396 0.3048)
			(stroke
				(width 0.1)
				(type default)
			)
			(layer "B.Fab")
		)
		(fp_line
			(start -0.67945 -0.3048)
			(end -0.67945 0.3048)
			(stroke
				(width 0.1)
				(type default)
			)
			(layer "B.Fab")
		)
		(pad "1" smd circle
			(at 0.40005 0)
			(size 0 0)
			(layers "B.Cu" "B.Mask" "B.Paste")
			(net "GND")
		)
		(pad "2" smd circle
			(at -0.40005 0)
			(size 0 0)
			(layers "B.Cu" "B.Mask" "B.Paste")
			(net "RST_BIC_USB_HUB_R_N")
		)
	)
	(footprint ""
		(layer "B.Cu")
		(at 405.183848 -308.724808 -90)
		(property "Reference" "R1459"
			(at 0 0 90)
			(layer "B.SilkS")
			(hide yes)
			(effects
				(font
					(size 1.27 1.27)
				)
				(justify mirror)
			)
		)
		(property "Value" ""
			(at 0 0 90)
			(layer "B.Fab")
			(effects
				(font
					(size 1.27 1.27)
				)
				(justify mirror)
			)
		)
		(duplicate_pad_numbers_are_jumpers no)
		(fp_line
			(start -0.7874 0.4064)
			(end 0.7874 0.4064)
			(stroke
				(width 0.1524)
				(type default)
			)
			(layer "B.SilkS")
		)
		(fp_line
			(start 0.7874 0.4064)
			(end 0.7874 -0.4064)
			(stroke
				(width 0.1524)
				(type default)
			)
			(layer "B.SilkS")
		)
		(fp_line
			(start -0.7874 -0.4064)
			(end -0.7874 0.4064)
			(stroke
				(width 0.1524)
				(type default)
			)
			(layer "B.SilkS")
		)
		(fp_line
			(start 0.7874 -0.4064)
			(end -0.7874 -0.4064)
			(stroke
				(width 0.1524)
				(type default)
			)
			(layer "B.SilkS")
		)
		(fp_line
			(start -0.67945 0.3048)
			(end -0.120396 0.3048)
			(stroke
				(width 0.1)
				(type default)
			)
			(layer "B.Fab")
		)
		(fp_line
			(start -0.120396 0.3048)
			(end -0.120396 0.2794)
			(stroke
				(width 0.1)
				(type default)
			)
			(layer "B.Fab")
		)
		(fp_line
			(start 0.12065 0.3048)
			(end 0.67945 0.3048)
			(stroke
				(width 0.1)
				(type default)
			)
			(layer "B.Fab")
		)
		(fp_line
			(start 0.67945 0.3048)
			(end 0.67945 -0.305054)
			(stroke
				(width 0.1)
				(type default)
			)
			(layer "B.Fab")
		)
		(fp_line
			(start -0.120396 0.2794)
			(end 0.12065 0.2794)
			(stroke
				(width 0.1)
				(type default)
			)
			(layer "B.Fab")
		)
		(fp_line
			(start 0.12065 0.2794)
			(end 0.12065 0.3048)
			(stroke
				(width 0.1)
				(type default)
			)
			(layer "B.Fab")
		)
		(fp_line
			(start -0.12065 -0.2794)
			(end -0.12065 -0.3048)
			(stroke
				(width 0.1)
				(type default)
			)
			(layer "B.Fab")
		)
		(fp_line
			(start 0.12065 -0.2794)
			(end -0.12065 -0.2794)
			(stroke
				(width 0.1)
				(type default)
			)
			(layer "B.Fab")
		)
		(fp_line
			(start -0.67945 -0.3048)
			(end -0.67945 0.3048)
			(stroke
				(width 0.1)
				(type default)
			)
			(layer "B.Fab")
		)
		(fp_line
			(start -0.12065 -0.3048)
			(end -0.67945 -0.3048)
			(stroke
				(width 0.1)
				(type default)
			)
			(layer "B.Fab")
		)
		(fp_line
			(start 0.12065 -0.305054)
			(end 0.12065 -0.2794)
			(stroke
				(width 0.1)
				(type default)
			)
			(layer "B.Fab")
		)
		(fp_line
			(start 0.67945 -0.305054)
			(end 0.12065 -0.305054)
			(stroke
				(width 0.1)
				(type default)
			)
			(layer "B.Fab")
		)
		(pad "1" smd circle
			(at 0.40005 0 90)
			(size 0 0)
			(layers "B.Cu" "B.Mask" "B.Paste")
			(net "TP_PEX3_TRST_L")
		)
		(pad "2" smd circle
			(at -0.40005 0 90)
			(size 0 0)
			(layers "B.Cu" "B.Mask" "B.Paste")
			(net "GND")
		)
	)
	(footprint ""
		(layer "B.Cu")
		(at 241.660934 -278.639778 -90)
		(property "Reference" "C4348"
			(at 0 0 90)
			(layer "B.SilkS")
			(hide yes)
			(effects
				(font
					(size 1.27 1.27)
				)
				(justify mirror)
			)
		)
		(property "Value" ""
			(at 0 0 90)
			(layer "B.Fab")
			(effects
				(font
					(size 1.27 1.27)
				)
				(justify mirror)
			)
		)
		(duplicate_pad_numbers_are_jumpers no)
		(fp_line
			(start -0.299974 0.150114)
			(end 0.299974 0.150114)
			(stroke
				(width 0.1)
				(type default)
			)
			(layer "B.Fab")
		)
		(fp_line
			(start 0.299974 0.150114)
			(end 0.299974 -0.150114)
			(stroke
				(width 0.1)
				(type default)
			)
			(layer "B.Fab")
		)
		(fp_line
			(start -0.299974 -0.150114)
			(end -0.299974 0.150114)
			(stroke
				(width 0.1)
				(type default)
			)
			(layer "B.Fab")
		)
		(fp_line
			(start 0.299974 -0.150114)
			(end -0.299974 -0.150114)
			(stroke
				(width 0.1)
				(type default)
			)
			(layer "B.Fab")
		)
		(pad "1" smd rect
			(at 0.2667 0 90)
			(size 0.3048 0.381)
			(layers "B.Cu" "B.Mask" "B.Paste")
			(net "P1V25_PEX2")
		)
		(pad "2" smd rect
			(at -0.2667 0 90)
			(size 0.3048 0.381)
			(layers "B.Cu" "B.Mask" "B.Paste")
			(net "GND")
		)
	)
	(footprint ""
		(layer "B.Cu")
		(at 182.87492 -293.99992 90)
		(property "Reference" "C1420"
			(at 0 0 90)
			(layer "B.SilkS")
			(hide yes)
			(effects
				(font
					(size 1.27 1.27)
				)
				(justify mirror)
			)
		)
		(property "Value" ""
			(at 0 0 90)
			(layer "B.Fab")
			(effects
				(font
					(size 1.27 1.27)
				)
				(justify mirror)
			)
		)
		(duplicate_pad_numbers_are_jumpers no)
		(fp_line
			(start 0.299974 -0.150114)
			(end -0.299974 -0.150114)
			(stroke
				(width 0.1)
				(type default)
			)
			(layer "B.Fab")
		)
		(fp_line
			(start -0.299974 -0.150114)
			(end -0.299974 0.150114)
			(stroke
				(width 0.1)
				(type default)
			)
			(layer "B.Fab")
		)
		(fp_line
			(start 0.299974 0.150114)
			(end 0.299974 -0.150114)
			(stroke
				(width 0.1)
				(type default)
			)
			(layer "B.Fab")
		)
		(fp_line
			(start -0.299974 0.150114)
			(end 0.299974 0.150114)
			(stroke
				(width 0.1)
				(type default)
			)
			(layer "B.Fab")
		)
		(pad "1" smd rect
			(at 0.2667 0 270)
			(size 0.3048 0.381)
			(layers "B.Cu" "B.Mask" "B.Paste")
			(net "P0V8_SERDES_VDDA_PEX1")
		)
		(pad "2" smd rect
			(at -0.2667 0 270)
			(size 0.3048 0.381)
			(layers "B.Cu" "B.Mask" "B.Paste")
			(net "GND")
		)
	)
	(footprint ""
		(layer "B.Cu")
		(at 87.175848 -459.136496)
		(property "Reference" "X26"
			(at 0.1778 -1.92913 0)
			(unlocked yes)
			(layer "B.SilkS")
			(effects
				(font
					(size 0.7874 0.5842)
					(thickness 0.1524)
				)
				(justify left mirror)
			)
		)
		(property "Value" ""
			(at 0 0 0)
			(layer "B.Fab")
			(effects
				(font
					(size 1.27 1.27)
				)
				(justify mirror)
			)
		)
		(property "Device Type" "TP_TDR_4P_FTS_MPKT4_H025P0200_IO_TP15_TP_TDR_4P_DIP"
			(at -1.30175 1.27 270)
			(unlocked yes)
			(layer "B.Fab")
			(hide yes)
			(effects
				(font
					(size 0.635 0.4064)
					(thickness 0.1524)
				)
				(justify mirror)
			)
		)
		(property "User Part Number" "TP15"
			(at -1.30175 1.27 270)
			(unlocked yes)
			(layer "Cmts.User")
			(hide yes)
			(effects
				(font
					(size 0.635 0.4064)
					(thickness 0.1524)
				)
				(justify mirror)
			)
		)
		(duplicate_pad_numbers_are_jumpers no)
		(fp_line
			(start -2.54 -1.27)
			(end 0 -1.27)
			(stroke
				(width 0.1524)
				(type default)
			)
			(layer "B.SilkS")
		)
		(fp_line
			(start -2.54 -1.1303)
			(end -2.54 -1.27)
			(stroke
				(width 0.1524)
				(type default)
			)
			(layer "B.SilkS")
		)
		(fp_line
			(start -2.54 1.4097)
			(end -2.54 1.1303)
			(stroke
				(width 0.1524)
				(type default)
			)
			(layer "B.SilkS")
		)
		(fp_line
			(start -2.54 3.81)
			(end -2.54 3.6703)
			(stroke
				(width 0.1524)
				(type default)
			)
			(layer "B.SilkS")
		)
		(fp_line
			(start 0 -1.27)
			(end 0 -0.635)
			(stroke
				(width 0.1524)
				(type default)
			)
			(layer "B.SilkS")
		)
		(fp_line
			(start 0 0.635)
			(end 0 1.905)
			(stroke
				(width 0.1524)
				(type default)
			)
			(layer "B.SilkS")
		)
		(fp_line
			(start 0 3.175)
			(end 0 3.81)
			(stroke
				(width 0.1524)
				(type default)
			)
			(layer "B.SilkS")
		)
		(fp_line
			(start 0 3.81)
			(end -2.54 3.81)
			(stroke
				(width 0.1524)
				(type default)
			)
			(layer "B.SilkS")
		)
		(fp_poly
			(pts
				(xy 0.761746 0) (xy 2.285746 -0.762) (xy 2.285746 0.762)
			)
			(stroke
				(width 0)
				(type default)
			)
			(fill yes)
			(layer "B.SilkS")
		)
		(fp_line
			(start -2.54 -1.27)
			(end 0 -1.27)
			(stroke
				(width 0.1)
				(type default)
			)
			(layer "B.Fab")
		)
		(fp_line
			(start -2.54 3.81)
			(end -2.54 -1.27)
			(stroke
				(width 0.1)
				(type default)
			)
			(layer "B.Fab")
		)
		(fp_line
			(start 0 -1.27)
			(end 0 3.81)
			(stroke
				(width 0.1)
				(type default)
			)
			(layer "B.Fab")
		)
		(fp_line
			(start 0 3.81)
			(end -2.54 3.81)
			(stroke
				(width 0.1)
				(type default)
			)
			(layer "B.Fab")
		)
		(fp_poly
			(pts
				(xy 0.761746 0) (xy 2.285746 -0.762) (xy 2.285746 0.762)
			)
			(stroke
				(width 0)
				(type default)
			)
			(fill yes)
			(layer "B.Fab")
		)
		(pad "1" thru_hole circle
			(at 0 0 180)
			(size 1.0033 1.0033)
			(drill 0.249936)
			(layers "*.Cu" "*.Mask")
			(remove_unused_layers no)
			(net "TDR_DIFF_85_IN4_DIP")
			(clearance 0.10795)
			(padstack
				(mode front_inner_back)
				(layer "Inner"
					(shape circle)
					(size 0.8001 0.8001)
					(clearance 0.1524)
				)
				(layer "B.Cu"
					(shape circle)
					(size 1.0033 1.0033)
					(thermal_gap 0.10795)
					(clearance 0.10795)
				)
			)
		)
		(pad "2" thru_hole circle
			(at -2.54 0 180)
			(size 1.9939 1.9939)
			(drill 0.249936)
			(layers "*.Cu" "*.Mask")
			(remove_unused_layers no)
			(net "COUPON_GND1")
			(clearance 0.10795)
			(padstack
				(mode front_inner_back)
				(layer "Inner"
					(shape circle)
					(size 0.8001 0.8001)
					(clearance 0.1524)
				)
				(layer "B.Cu"
					(shape circle)
					(size 1.9939 1.9939)
					(thermal_gap 0.10795)
					(clearance 0.10795)
				)
			)
		)
		(pad "3" thru_hole circle
			(at -2.54 2.54 180)
			(size 1.9939 1.9939)
			(drill 0.249936)
			(layers "*.Cu" "*.Mask")
			(remove_unused_layers no)
			(net "COUPON_GND1")
			(clearance 0.10795)
			(padstack
				(mode front_inner_back)
				(layer "Inner"
					(shape circle)
					(size 0.8001 0.8001)
					(clearance 0.1524)
				)
				(layer "B.Cu"
					(shape circle)
					(size 1.9939 1.9939)
					(thermal_gap 0.10795)
					(clearance 0.10795)
				)
			)
		)
		(pad "4" thru_hole circle
			(at 0 2.54 180)
			(size 1.0033 1.0033)
			(drill 0.249936)
			(layers "*.Cu" "*.Mask")
			(remove_unused_layers no)
			(net "TDR_DIFF_85_IN4_DIN")
			(clearance 0.10795)
			(padstack
				(mode front_inner_back)
				(layer "Inner"
					(shape circle)
					(size 0.8001 0.8001)
					(clearance 0.1524)
				)
				(layer "B.Cu"
					(shape circle)
					(size 1.0033 1.0033)
					(thermal_gap 0.10795)
					(clearance 0.10795)
				)
			)
		)
	)
	(footprint ""
		(layer "B.Cu")
		(at 129.243074 -277.644352 180)
		(property "Reference" "PC6612"
			(at 0 0 0)
			(layer "B.SilkS")
			(hide yes)
			(effects
				(font
					(size 1.27 1.27)
				)
				(justify mirror)
			)
		)
		(property "Value" ""
			(at 0 0 0)
			(layer "B.Fab")
			(effects
				(font
					(size 1.27 1.27)
				)
				(justify mirror)
			)
		)
		(duplicate_pad_numbers_are_jumpers no)
		(fp_line
			(start 1.524 0.762)
			(end 1.524 -0.762)
			(stroke
				(width 0.1524)
				(type default)
			)
			(layer "B.SilkS")
		)
		(fp_line
			(start 1.524 -0.762)
			(end -1.524 -0.762)
			(stroke
				(width 0.1524)
				(type default)
			)
			(layer "B.SilkS")
		)
		(fp_line
			(start -1.524 0.762)
			(end 1.524 0.762)
			(stroke
				(width 0.1524)
				(type default)
			)
			(layer "B.SilkS")
		)
		(fp_line
			(start -1.524 -0.762)
			(end -1.524 0.762)
			(stroke
				(width 0.1524)
				(type default)
			)
			(layer "B.SilkS")
		)
		(fp_line
			(start 1.1049 0.724916)
			(end -1.1049 0.724916)
			(stroke
				(width 0.1)
				(type default)
			)
			(layer "B.Fab")
		)
		(fp_line
			(start 1.1049 -0.724916)
			(end 1.1049 0.724916)
			(stroke
				(width 0.1)
				(type default)
			)
			(layer "B.Fab")
		)
		(fp_line
			(start -1.1049 0.724916)
			(end -1.1049 -0.724916)
			(stroke
				(width 0.1)
				(type default)
			)
			(layer "B.Fab")
		)
		(fp_line
			(start -1.1049 -0.724916)
			(end 1.1049 -0.724916)
			(stroke
				(width 0.1)
				(type default)
			)
			(layer "B.Fab")
		)
		(pad "1" smd rect
			(at 0.889 0 180)
			(size 1.016 1.27)
			(layers "B.Cu" "B.Mask" "B.Paste")
			(net "SW_P12V_P0V8_PEX1_FLT")
		)
		(pad "2" smd rect
			(at -0.889 0 180)
			(size 1.016 1.27)
			(layers "B.Cu" "B.Mask" "B.Paste")
			(net "GND")
		)
	)
	(footprint ""
		(layer "B.Cu")
		(at 55.374794 -297.79976 90)
		(property "Reference" "C1151"
			(at 0 0 90)
			(layer "B.SilkS")
			(hide yes)
			(effects
				(font
					(size 1.27 1.27)
				)
				(justify mirror)
			)
		)
		(property "Value" ""
			(at 0 0 90)
			(layer "B.Fab")
			(effects
				(font
					(size 1.27 1.27)
				)
				(justify mirror)
			)
		)
		(duplicate_pad_numbers_are_jumpers no)
		(fp_line
			(start 0.299974 -0.150114)
			(end -0.299974 -0.150114)
			(stroke
				(width 0.1)
				(type default)
			)
			(layer "B.Fab")
		)
		(fp_line
			(start -0.299974 -0.150114)
			(end -0.299974 0.150114)
			(stroke
				(width 0.1)
				(type default)
			)
			(layer "B.Fab")
		)
		(fp_line
			(start 0.299974 0.150114)
			(end 0.299974 -0.150114)
			(stroke
				(width 0.1)
				(type default)
			)
			(layer "B.Fab")
		)
		(fp_line
			(start -0.299974 0.150114)
			(end 0.299974 0.150114)
			(stroke
				(width 0.1)
				(type default)
			)
			(layer "B.Fab")
		)
		(pad "1" smd rect
			(at 0.2667 0 270)
			(size 0.3048 0.381)
			(layers "B.Cu" "B.Mask" "B.Paste")
			(net "P0V8_PEX0")
		)
		(pad "2" smd rect
			(at -0.2667 0 270)
			(size 0.3048 0.381)
			(layers "B.Cu" "B.Mask" "B.Paste")
			(net "GND")
		)
	)
)
